# T6G (Grand Teton) — schematic netlist excerpt (pin names and nets, part order shuffled) for the footprints in the layout excerpt that follows; sources: Cadence DE-HDL packaged netlist, KiCad conversion of 04192023_DAF0TMB3IC0_F0TG_MB_C_brd_V02_OCP.brd

R2946  Q_RES  4.7K 5% EMPTY  pkg 0402LF  page 241 : A = P3V3_AUX ; B = FM_GPU_HSC_EN_BUF_R
R6317  Q_RES  0 5% CHIP  pkg 0402LF  page 178 : A = USB_HUB2_MRP_RESET_N ; B = USB_HUB2_TI_USB_VBUS_MRP_RESET_N

(kicad_pcb
	(version 20260206)
	(generator "pcbnew")
	(generator_version "10.0")
	(general
		(thickness 1.6)
		(legacy_teardrops no)
	)
	(paper "A4")
	(title_block
		(title "04192023_DAF0TMB3IC0_F0TG_MB_C_brd_V02_OCP.brd")
		(comment 1 "Grand Teton / footprints 4864-4865 of 8354")
	)
	(layers
		(0 "F.Cu" signal "TOP")
		(4 "In1.Cu" signal "GND")
		(6 "In2.Cu" signal "IN1")
		(8 "In3.Cu" signal "GND1")
		(10 "In4.Cu" signal "IN2")
		(12 "In5.Cu" signal "GND2")
		(14 "In6.Cu" signal "IN3")
		(16 "In7.Cu" signal "GND3")
		(18 "In8.Cu" signal "VCC")
		(20 "In9.Cu" signal "VCC1")
		(22 "In10.Cu" signal "GND4")
		(24 "In11.Cu" signal "IN4")
		(26 "In12.Cu" signal "GND5")
		(28 "In13.Cu" signal "IN5")
		(30 "In14.Cu" signal "GND6")
		(32 "In15.Cu" signal "IN6")
		(34 "In16.Cu" signal "GND7")
		(2 "B.Cu" signal "BOTTOM")
		(9 "F.Adhes" user "F.Adhesive")
		(11 "B.Adhes" user "B.Adhesive")
		(13 "F.Paste" user "Package Geometry/Pastemask Top")
		(15 "B.Paste" user "Package Geometry/Pastemask Bottom")
		(5 "F.SilkS" user "Ref Des/Silkscreen Top")
		(7 "B.SilkS" user "Ref Des/Silkscreen Bottom")
		(1 "F.Mask" user "Board Geometry/Soldermask Top")
		(3 "B.Mask" user "Board Geometry/Soldermask Bottom")
		(17 "Dwgs.User" user "User.Drawings")
		(19 "Cmts.User" user "User.Comments")
		(21 "Eco1.User" user "User.Eco1")
		(23 "Eco2.User" user "User.Eco2")
		(25 "Edge.Cuts" user "Board Geometry/Outline")
		(27 "Margin" user)
		(31 "F.CrtYd" user "Package Geometry/Place Bound Top")
		(29 "B.CrtYd" user "Package Geometry/Place Bound Bottom")
		(35 "F.Fab" user "Ref Des/Assembly Top")
		(33 "B.Fab" user "Ref Des/Assembly Bottom")
	)
	(footprint ""
		(layer "F.Cu")
		(at 102.437946 -52.86248 -90)
		(property "Reference" "R6317"
			(at 0 0 270)
			(layer "F.SilkS")
			(hide yes)
			(effects
				(font
					(size 1.27 1.27)
				)
			)
		)
		(property "Value" ""
			(at 0 0 270)
			(layer "F.Fab")
			(effects
				(font
					(size 1.27 1.27)
				)
			)
		)
		(duplicate_pad_numbers_are_jumpers no)
		(fp_line
			(start -0.7874 0.4064)
			(end -0.7874 -0.4064)
			(stroke
				(width 0.1524)
				(type default)
			)
			(layer "F.SilkS")
		)
		(fp_line
			(start 0.7874 0.4064)
			(end -0.7874 0.4064)
			(stroke
				(width 0.1524)
				(type default)
			)
			(layer "F.SilkS")
		)
		(fp_line
			(start -0.7874 -0.4064)
			(end 0.7874 -0.4064)
			(stroke
				(width 0.1524)
				(type default)
			)
			(layer "F.SilkS")
		)
		(fp_line
			(start 0.7874 -0.4064)
			(end 0.7874 0.4064)
			(stroke
				(width 0.1524)
				(type default)
			)
			(layer "F.SilkS")
		)
		(fp_line
			(start -0.67945 0.3048)
			(end -0.67945 -0.305054)
			(stroke
				(width 0.1)
				(type default)
			)
			(layer "F.Fab")
		)
		(fp_line
			(start -0.12065 0.3048)
			(end -0.67945 0.3048)
			(stroke
				(width 0.1)
				(type default)
			)
			(layer "F.Fab")
		)
		(fp_line
			(start 0.120396 0.3048)
			(end 0.120396 0.2794)
			(stroke
				(width 0.1)
				(type default)
			)
			(layer "F.Fab")
		)
		(fp_line
			(start 0.67945 0.3048)
			(end 0.120396 0.3048)
			(stroke
				(width 0.1)
				(type default)
			)
			(layer "F.Fab")
		)
		(fp_line
			(start -0.12065 0.2794)
			(end -0.12065 0.3048)
			(stroke
				(width 0.1)
				(type default)
			)
			(layer "F.Fab")
		)
		(fp_line
			(start 0.120396 0.2794)
			(end -0.12065 0.2794)
			(stroke
				(width 0.1)
				(type default)
			)
			(layer "F.Fab")
		)
		(fp_line
			(start -0.12065 -0.2794)
			(end 0.12065 -0.2794)
			(stroke
				(width 0.1)
				(type default)
			)
			(layer "F.Fab")
		)
		(fp_line
			(start 0.12065 -0.2794)
			(end 0.12065 -0.3048)
			(stroke
				(width 0.1)
				(type default)
			)
			(layer "F.Fab")
		)
		(fp_line
			(start 0.12065 -0.3048)
			(end 0.67945 -0.3048)
			(stroke
				(width 0.1)
				(type default)
			)
			(layer "F.Fab")
		)
		(fp_line
			(start 0.67945 -0.3048)
			(end 0.67945 0.3048)
			(stroke
				(width 0.1)
				(type default)
			)
			(layer "F.Fab")
		)
		(fp_line
			(start -0.67945 -0.305054)
			(end -0.12065 -0.305054)
			(stroke
				(width 0.1)
				(type default)
			)
			(layer "F.Fab")
		)
		(fp_line
			(start -0.12065 -0.305054)
			(end -0.12065 -0.2794)
			(stroke
				(width 0.1)
				(type default)
			)
			(layer "F.Fab")
		)
		(pad "1" smd circle
			(at -0.40005 0 270)
			(size 0 0)
			(layers "F.Cu" "F.Mask" "F.Paste")
			(net "USB_HUB2_MRP_RESET_N")
		)
		(pad "2" smd circle
			(at 0.40005 0 270)
			(size 0 0)
			(layers "F.Cu" "F.Mask" "F.Paste")
			(net "USB_HUB2_TI_USB_VBUS_MRP_RESET_N")
		)
	)
	(footprint ""
		(layer "F.Cu")
		(at 192.53962 -422.804082 -90)
		(property "Reference" "R2946"
			(at 0 0 270)
			(layer "F.SilkS")
			(hide yes)
			(effects
				(font
					(size 1.27 1.27)
				)
			)
		)
		(property "Value" ""
			(at 0 0 270)
			(layer "F.Fab")
			(effects
				(font
					(size 1.27 1.27)
				)
			)
		)
		(duplicate_pad_numbers_are_jumpers no)
		(fp_line
			(start -0.7874 0.4064)
			(end -0.7874 -0.4064)
			(stroke
				(width 0.1524)
				(type default)
			)
			(layer "F.SilkS")
		)
		(fp_line
			(start 0.7874 0.4064)
			(end -0.7874 0.4064)
			(stroke
				(width 0.1524)
				(type default)
			)
			(layer "F.SilkS")
		)
		(fp_line
			(start -0.7874 -0.4064)
			(end 0.7874 -0.4064)
			(stroke
				(width 0.1524)
				(type default)
			)
			(layer "F.SilkS")
		)
		(fp_line
			(start 0.7874 -0.4064)
			(end 0.7874 0.4064)
			(stroke
				(width 0.1524)
				(type default)
			)
			(layer "F.SilkS")
		)
		(fp_line
			(start -0.67945 0.3048)
			(end -0.67945 -0.305054)
			(stroke
				(width 0.1)
				(type default)
			)
			(layer "F.Fab")
		)
		(fp_line
			(start -0.12065 0.3048)
			(end -0.67945 0.3048)
			(stroke
				(width 0.1)
				(type default)
			)
			(layer "F.Fab")
		)
		(fp_line
			(start 0.120396 0.3048)
			(end 0.120396 0.2794)
			(stroke
				(width 0.1)
				(type default)
			)
			(layer "F.Fab")
		)
		(fp_line
			(start 0.67945 0.3048)
			(end 0.120396 0.3048)
			(stroke
				(width 0.1)
				(type default)
			)
			(layer "F.Fab")
		)
		(fp_line
			(start -0.12065 0.2794)
			(end -0.12065 0.3048)
			(stroke
				(width 0.1)
				(type default)
			)
			(layer "F.Fab")
		)
		(fp_line
			(start 0.120396 0.2794)
			(end -0.12065 0.2794)
			(stroke
				(width 0.1)
				(type default)
			)
			(layer "F.Fab")
		)
		(fp_line
			(start -0.12065 -0.2794)
			(end 0.12065 -0.2794)
			(stroke
				(width 0.1)
				(type default)
			)
			(layer "F.Fab")
		)
		(fp_line
			(start 0.12065 -0.2794)
			(end 0.12065 -0.3048)
			(stroke
				(width 0.1)
				(type default)
			)
			(layer "F.Fab")
		)
		(fp_line
			(start 0.12065 -0.3048)
			(end 0.67945 -0.3048)
			(stroke
				(width 0.1)
				(type default)
			)
			(layer "F.Fab")
		)
		(fp_line
			(start 0.67945 -0.3048)
			(end 0.67945 0.3048)
			(stroke
				(width 0.1)
				(type default)
			)
			(layer "F.Fab")
		)
		(fp_line
			(start -0.67945 -0.305054)
			(end -0.12065 -0.305054)
			(stroke
				(width 0.1)
				(type default)
			)
			(layer "F.Fab")
		)
		(fp_line
			(start -0.12065 -0.305054)
			(end -0.12065 -0.2794)
			(stroke
				(width 0.1)
				(type default)
			)
			(layer "F.Fab")
		)
		(pad "1" smd circle
			(at -0.40005 0 270)
			(size 0 0)
			(layers "F.Cu" "F.Mask" "F.Paste")
			(net "P3V3_AUX")
		)
		(pad "2" smd circle
			(at 0.40005 0 270)
			(size 0 0)
			(layers "F.Cu" "F.Mask" "F.Paste")
			(net "FM_GPU_HSC_EN_BUF_R")
		)
	)
)
